(kicad_pcb
	(version 20260206)
	(generator "pcbnew")
	(generator_version "10.0")
	(general
		(thickness 1.6)
		(legacy_teardrops no)
	)
	(paper "A4")
	(title_block
		(title "03242023_DA0F0TMBIJ0_F0T_Motherboard_J_brd_V01_OCP.brd")
		(comment 1 "Grand Teton / footprints 469-475 of 6105")
	)
	(layers
		(0 "F.Cu" signal "TOP")
		(4 "In1.Cu" signal "GND")
		(6 "In2.Cu" signal "IN1")
		(8 "In3.Cu" signal "GND1")
		(10 "In4.Cu" signal "IN2")
		(12 "In5.Cu" signal "GND2")
		(14 "In6.Cu" signal "IN3")
		(16 "In7.Cu" signal "GND3")
		(18 "In8.Cu" signal "VCC")
		(20 "In9.Cu" signal "VCC1")
		(22 "In10.Cu" signal "GND4")
		(24 "In11.Cu" signal "IN4")
		(26 "In12.Cu" signal "GND5")
		(28 "In13.Cu" signal "IN5")
		(30 "In14.Cu" signal "GND6")
		(32 "In15.Cu" signal "IN6")
		(34 "In16.Cu" signal "GND7")
		(2 "B.Cu" signal "BOTTOM")
		(9 "F.Adhes" user "F.Adhesive")
		(11 "B.Adhes" user "B.Adhesive")
		(13 "F.Paste" user "Package Geometry/Pastemask Top")
		(15 "B.Paste" user "Package Geometry/Pastemask Bottom")
		(5 "F.SilkS" user "Ref Des/Silkscreen Top")
		(7 "B.SilkS" user "Ref Des/Silkscreen Bottom")
		(1 "F.Mask" user "Board Geometry/Soldermask Top")
		(3 "B.Mask" user "Board Geometry/Soldermask Bottom")
		(17 "Dwgs.User" user "User.Drawings")
		(19 "Cmts.User" user "User.Comments")
		(21 "Eco1.User" user "User.Eco1")
		(23 "Eco2.User" user "User.Eco2")
		(25 "Edge.Cuts" user "Board Geometry/Outline")
		(27 "Margin" user)
		(31 "F.CrtYd" user "Package Geometry/Place Bound Top")
		(29 "B.CrtYd" user "Package Geometry/Place Bound Bottom")
		(35 "F.Fab" user "Ref Des/Assembly Top")
		(33 "B.Fab" user "Ref Des/Assembly Bottom")
	)
	(footprint ""
		(layer "F.Cu")
		(at 104.89946 -344.029284 90)
		(property "Reference" "PC588"
			(at 0 0 90)
			(layer "F.SilkS")
			(hide yes)
			(effects
				(font
					(size 1.27 1.27)
				)
			)
		)
		(property "Value" ""
			(at 0 0 90)
			(layer "F.Fab")
			(effects
				(font
					(size 1.27 1.27)
				)
			)
		)
		(duplicate_pad_numbers_are_jumpers no)
		(fp_line
			(start -3.400044 1.249934)
			(end 3.400044 1.249934)
			(stroke
				(width 0.1524)
				(type default)
			)
			(layer "F.SilkS")
		)
		(fp_circle
			(center 0 1.249934)
			(end 0 4.649978)
			(stroke
				(width 0.1524)
				(type default)
			)
			(fill no)
			(layer "F.SilkS")
		)
		(fp_poly
			(pts
				(arc
					(start -3.400044 1.249934)
					(mid 0 4.649978)
					(end 3.400044 1.249934)
				)
			)
			(stroke
				(width 0)
				(type default)
			)
			(fill yes)
			(layer "F.SilkS")
		)
		(fp_circle
			(center 0 1.249934)
			(end 0 4.649978)
			(stroke
				(width 0.1)
				(type default)
			)
			(fill no)
			(layer "F.Fab")
		)
		(pad "1" thru_hole rect
			(at 0 0 90)
			(size 1.524 1.524)
			(drill 1.016)
			(layers "*.Cu" "*.Mask")
			(remove_unused_layers no)
			(net "SW_P12V_PVCCIN_CPU1_FLT")
			(clearance 0)
			(padstack
				(mode front_inner_back)
				(layer "Inner"
					(shape circle)
					(size 1.524 1.524)
					(clearance 0)
				)
				(layer "B.Cu"
					(shape rect)
					(size 1.524 1.524)
					(clearance 0)
				)
			)
		)
		(pad "2" thru_hole circle
			(at 0 2.500122 90)
			(size 1.524 1.524)
			(drill 1.016)
			(layers "*.Cu" "*.Mask")
			(remove_unused_layers no)
			(net "GND")
			(clearance 0)
		)
	)
	(footprint ""
		(layer "F.Cu")
		(at 357.683816 -336.192368 90)
		(property "Reference" "PC271"
			(at 0 0 90)
			(layer "F.SilkS")
			(hide yes)
			(effects
				(font
					(size 1.27 1.27)
				)
			)
		)
		(property "Value" ""
			(at 0 0 90)
			(layer "F.Fab")
			(effects
				(font
					(size 1.27 1.27)
				)
			)
		)
		(duplicate_pad_numbers_are_jumpers no)
		(fp_line
			(start 0.7874 -0.4064)
			(end 0.7874 0.4064)
			(stroke
				(width 0.1524)
				(type default)
			)
			(layer "F.SilkS")
		)
		(fp_line
			(start -0.7874 -0.4064)
			(end 0.7874 -0.4064)
			(stroke
				(width 0.1524)
				(type default)
			)
			(layer "F.SilkS")
		)
		(fp_line
			(start 0.7874 0.4064)
			(end -0.7874 0.4064)
			(stroke
				(width 0.1524)
				(type default)
			)
			(layer "F.SilkS")
		)
		(fp_line
			(start -0.7874 0.4064)
			(end -0.7874 -0.4064)
			(stroke
				(width 0.1524)
				(type default)
			)
			(layer "F.SilkS")
		)
		(fp_line
			(start -0.12065 -0.305054)
			(end -0.12065 -0.2794)
			(stroke
				(width 0.1)
				(type default)
			)
			(layer "F.Fab")
		)
		(fp_line
			(start -0.67945 -0.305054)
			(end -0.12065 -0.305054)
			(stroke
				(width 0.1)
				(type default)
			)
			(layer "F.Fab")
		)
		(fp_line
			(start 0.67945 -0.3048)
			(end 0.67945 0.3048)
			(stroke
				(width 0.1)
				(type default)
			)
			(layer "F.Fab")
		)
		(fp_line
			(start 0.12065 -0.3048)
			(end 0.67945 -0.3048)
			(stroke
				(width 0.1)
				(type default)
			)
			(layer "F.Fab")
		)
		(fp_line
			(start 0.12065 -0.2794)
			(end 0.12065 -0.3048)
			(stroke
				(width 0.1)
				(type default)
			)
			(layer "F.Fab")
		)
		(fp_line
			(start -0.12065 -0.2794)
			(end 0.12065 -0.2794)
			(stroke
				(width 0.1)
				(type default)
			)
			(layer "F.Fab")
		)
		(fp_line
			(start 0.120396 0.2794)
			(end -0.12065 0.2794)
			(stroke
				(width 0.1)
				(type default)
			)
			(layer "F.Fab")
		)
		(fp_line
			(start -0.12065 0.2794)
			(end -0.12065 0.3048)
			(stroke
				(width 0.1)
				(type default)
			)
			(layer "F.Fab")
		)
		(fp_line
			(start 0.67945 0.3048)
			(end 0.120396 0.3048)
			(stroke
				(width 0.1)
				(type default)
			)
			(layer "F.Fab")
		)
		(fp_line
			(start 0.120396 0.3048)
			(end 0.120396 0.2794)
			(stroke
				(width 0.1)
				(type default)
			)
			(layer "F.Fab")
		)
		(fp_line
			(start -0.12065 0.3048)
			(end -0.67945 0.3048)
			(stroke
				(width 0.1)
				(type default)
			)
			(layer "F.Fab")
		)
		(fp_line
			(start -0.67945 0.3048)
			(end -0.67945 -0.305054)
			(stroke
				(width 0.1)
				(type default)
			)
			(layer "F.Fab")
		)
		(pad "1" smd circle
			(at -0.40005 0 90)
			(size 0 0)
			(layers "F.Cu" "F.Mask" "F.Paste")
			(net "PVCCIN_CPU0_VDD3")
		)
		(pad "2" smd circle
			(at 0.40005 0 90)
			(size 0 0)
			(layers "F.Cu" "F.Mask" "F.Paste")
			(net "GND")
		)
	)
	(footprint ""
		(layer "F.Cu")
		(at 122.636534 -40.351456)
		(property "Reference" "C1882"
			(at 0 0 0)
			(layer "F.SilkS")
			(hide yes)
			(effects
				(font
					(size 1.27 1.27)
				)
			)
		)
		(property "Value" ""
			(at 0 0 0)
			(layer "F.Fab")
			(effects
				(font
					(size 1.27 1.27)
				)
			)
		)
		(duplicate_pad_numbers_are_jumpers no)
		(fp_line
			(start -0.7874 -0.4064)
			(end 0.7874 -0.4064)
			(stroke
				(width 0.1524)
				(type default)
			)
			(layer "F.SilkS")
		)
		(fp_line
			(start -0.7874 0.4064)
			(end -0.7874 -0.4064)
			(stroke
				(width 0.1524)
				(type default)
			)
			(layer "F.SilkS")
		)
		(fp_line
			(start 0.7874 -0.4064)
			(end 0.7874 0.4064)
			(stroke
				(width 0.1524)
				(type default)
			)
			(layer "F.SilkS")
		)
		(fp_line
			(start 0.7874 0.4064)
			(end -0.7874 0.4064)
			(stroke
				(width 0.1524)
				(type default)
			)
			(layer "F.SilkS")
		)
		(fp_line
			(start -0.67945 -0.305054)
			(end -0.12065 -0.305054)
			(stroke
				(width 0.1)
				(type default)
			)
			(layer "F.Fab")
		)
		(fp_line
			(start -0.67945 0.3048)
			(end -0.67945 -0.305054)
			(stroke
				(width 0.1)
				(type default)
			)
			(layer "F.Fab")
		)
		(fp_line
			(start -0.12065 -0.305054)
			(end -0.12065 -0.2794)
			(stroke
				(width 0.1)
				(type default)
			)
			(layer "F.Fab")
		)
		(fp_line
			(start -0.12065 -0.2794)
			(end 0.12065 -0.2794)
			(stroke
				(width 0.1)
				(type default)
			)
			(layer "F.Fab")
		)
		(fp_line
			(start -0.12065 0.2794)
			(end -0.12065 0.3048)
			(stroke
				(width 0.1)
				(type default)
			)
			(layer "F.Fab")
		)
		(fp_line
			(start -0.12065 0.3048)
			(end -0.67945 0.3048)
			(stroke
				(width 0.1)
				(type default)
			)
			(layer "F.Fab")
		)
		(fp_line
			(start 0.120396 0.2794)
			(end -0.12065 0.2794)
			(stroke
				(width 0.1)
				(type default)
			)
			(layer "F.Fab")
		)
		(fp_line
			(start 0.120396 0.3048)
			(end 0.120396 0.2794)
			(stroke
				(width 0.1)
				(type default)
			)
			(layer "F.Fab")
		)
		(fp_line
			(start 0.12065 -0.3048)
			(end 0.67945 -0.3048)
			(stroke
				(width 0.1)
				(type default)
			)
			(layer "F.Fab")
		)
		(fp_line
			(start 0.12065 -0.2794)
			(end 0.12065 -0.3048)
			(stroke
				(width 0.1)
				(type default)
			)
			(layer "F.Fab")
		)
		(fp_line
			(start 0.67945 -0.3048)
			(end 0.67945 0.3048)
			(stroke
				(width 0.1)
				(type default)
			)
			(layer "F.Fab")
		)
		(fp_line
			(start 0.67945 0.3048)
			(end 0.120396 0.3048)
			(stroke
				(width 0.1)
				(type default)
			)
			(layer "F.Fab")
		)
		(pad "1" smd circle
			(at -0.40005 0)
			(size 0 0)
			(layers "F.Cu" "F.Mask" "F.Paste")
			(net "P3V3_AUX")
		)
		(pad "2" smd circle
			(at 0.40005 0)
			(size 0 0)
			(layers "F.Cu" "F.Mask" "F.Paste")
			(net "GND")
		)
	)
	(footprint ""
		(layer "F.Cu")
		(at 263.542526 -94.888558)
		(property "Reference" "C108"
			(at 0 0 0)
			(layer "F.SilkS")
			(hide yes)
			(effects
				(font
					(size 1.27 1.27)
				)
			)
		)
		(property "Value" ""
			(at 0 0 0)
			(layer "F.Fab")
			(effects
				(font
					(size 1.27 1.27)
				)
			)
		)
		(duplicate_pad_numbers_are_jumpers no)
		(fp_line
			(start -1.2954 -0.5842)
			(end 1.2954 -0.5842)
			(stroke
				(width 0.1524)
				(type default)
			)
			(layer "F.SilkS")
		)
		(fp_line
			(start -1.2954 0.5842)
			(end -1.2954 -0.5842)
			(stroke
				(width 0.1524)
				(type default)
			)
			(layer "F.SilkS")
		)
		(fp_line
			(start 0 -0.5842)
			(end 0 0.5842)
			(stroke
				(width 0.1524)
				(type default)
			)
			(layer "F.SilkS")
		)
		(fp_line
			(start 1.2954 -0.5842)
			(end 1.2954 0.5842)
			(stroke
				(width 0.1524)
				(type default)
			)
			(layer "F.SilkS")
		)
		(fp_line
			(start 1.2954 0.5842)
			(end -1.2954 0.5842)
			(stroke
				(width 0.1524)
				(type default)
			)
			(layer "F.SilkS")
		)
		(fp_line
			(start -1.1938 -0.4064)
			(end -0.8636 -0.4064)
			(stroke
				(width 0.1)
				(type default)
			)
			(layer "F.Fab")
		)
		(fp_line
			(start -1.1938 0.4064)
			(end -1.1938 -0.4064)
			(stroke
				(width 0.1)
				(type default)
			)
			(layer "F.Fab")
		)
		(fp_line
			(start -0.8636 -0.4572)
			(end 0.8636 -0.4572)
			(stroke
				(width 0.1)
				(type default)
			)
			(layer "F.Fab")
		)
		(fp_line
			(start -0.8636 -0.4064)
			(end -0.8636 -0.4572)
			(stroke
				(width 0.1)
				(type default)
			)
			(layer "F.Fab")
		)
		(fp_line
			(start -0.8636 0.4064)
			(end -1.1938 0.4064)
			(stroke
				(width 0.1)
				(type default)
			)
			(layer "F.Fab")
		)
		(fp_line
			(start -0.8636 0.4572)
			(end -0.8636 0.4064)
			(stroke
				(width 0.1)
				(type default)
			)
			(layer "F.Fab")
		)
		(fp_line
			(start 0.8636 -0.4572)
			(end 0.8636 -0.4064)
			(stroke
				(width 0.1)
				(type default)
			)
			(layer "F.Fab")
		)
		(fp_line
			(start 0.8636 -0.4064)
			(end 1.1938 -0.4064)
			(stroke
				(width 0.1)
				(type default)
			)
			(layer "F.Fab")
		)
		(fp_line
			(start 0.8636 0.4064)
			(end 0.8636 0.4572)
			(stroke
				(width 0.1)
				(type default)
			)
			(layer "F.Fab")
		)
		(fp_line
			(start 0.8636 0.4572)
			(end -0.8636 0.4572)
			(stroke
				(width 0.1)
				(type default)
			)
			(layer "F.Fab")
		)
		(fp_line
			(start 1.1938 -0.4064)
			(end 1.1938 0.4064)
			(stroke
				(width 0.1)
				(type default)
			)
			(layer "F.Fab")
		)
		(fp_line
			(start 1.1938 0.4064)
			(end 0.8636 0.4064)
			(stroke
				(width 0.1)
				(type default)
			)
			(layer "F.Fab")
		)
		(pad "1" smd rect
			(at -0.7366 0 270)
			(size 0.7112 0.8128)
			(layers "F.Cu" "F.Mask" "F.Paste")
			(net "P3V3_AUX_CLK_GEN_VDD_CK440")
		)
		(pad "2" smd rect
			(at 0.7366 0 270)
			(size 0.7112 0.8128)
			(layers "F.Cu" "F.Mask" "F.Paste")
			(net "GND")
		)
	)
	(footprint ""
		(layer "F.Cu")
		(at 38.812724 -358.129586 -90)
		(property "Reference" "PC1370"
			(at 0 0 270)
			(layer "F.SilkS")
			(hide yes)
			(effects
				(font
					(size 1.27 1.27)
				)
			)
		)
		(property "Value" ""
			(at 0 0 270)
			(layer "F.Fab")
			(effects
				(font
					(size 1.27 1.27)
				)
			)
		)
		(duplicate_pad_numbers_are_jumpers no)
		(fp_line
			(start -0.7874 0.4064)
			(end -0.7874 -0.4064)
			(stroke
				(width 0.1524)
				(type default)
			)
			(layer "F.SilkS")
		)
		(fp_line
			(start 0.7874 0.4064)
			(end -0.7874 0.4064)
			(stroke
				(width 0.1524)
				(type default)
			)
			(layer "F.SilkS")
		)
		(fp_line
			(start -0.7874 -0.4064)
			(end 0.7874 -0.4064)
			(stroke
				(width 0.1524)
				(type default)
			)
			(layer "F.SilkS")
		)
		(fp_line
			(start 0.7874 -0.4064)
			(end 0.7874 0.4064)
			(stroke
				(width 0.1524)
				(type default)
			)
			(layer "F.SilkS")
		)
		(fp_line
			(start -0.67945 0.3048)
			(end -0.67945 -0.305054)
			(stroke
				(width 0.1)
				(type default)
			)
			(layer "F.Fab")
		)
		(fp_line
			(start -0.12065 0.3048)
			(end -0.67945 0.3048)
			(stroke
				(width 0.1)
				(type default)
			)
			(layer "F.Fab")
		)
		(fp_line
			(start 0.120396 0.3048)
			(end 0.120396 0.2794)
			(stroke
				(width 0.1)
				(type default)
			)
			(layer "F.Fab")
		)
		(fp_line
			(start 0.67945 0.3048)
			(end 0.120396 0.3048)
			(stroke
				(width 0.1)
				(type default)
			)
			(layer "F.Fab")
		)
		(fp_line
			(start -0.12065 0.2794)
			(end -0.12065 0.3048)
			(stroke
				(width 0.1)
				(type default)
			)
			(layer "F.Fab")
		)
		(fp_line
			(start 0.120396 0.2794)
			(end -0.12065 0.2794)
			(stroke
				(width 0.1)
				(type default)
			)
			(layer "F.Fab")
		)
		(fp_line
			(start -0.12065 -0.2794)
			(end 0.12065 -0.2794)
			(stroke
				(width 0.1)
				(type default)
			)
			(layer "F.Fab")
		)
		(fp_line
			(start 0.12065 -0.2794)
			(end 0.12065 -0.3048)
			(stroke
				(width 0.1)
				(type default)
			)
			(layer "F.Fab")
		)
		(fp_line
			(start 0.12065 -0.3048)
			(end 0.67945 -0.3048)
			(stroke
				(width 0.1)
				(type default)
			)
			(layer "F.Fab")
		)
		(fp_line
			(start 0.67945 -0.3048)
			(end 0.67945 0.3048)
			(stroke
				(width 0.1)
				(type default)
			)
			(layer "F.Fab")
		)
		(fp_line
			(start -0.67945 -0.305054)
			(end -0.12065 -0.305054)
			(stroke
				(width 0.1)
				(type default)
			)
			(layer "F.Fab")
		)
		(fp_line
			(start -0.12065 -0.305054)
			(end -0.12065 -0.2794)
			(stroke
				(width 0.1)
				(type default)
			)
			(layer "F.Fab")
		)
		(pad "1" smd circle
			(at -0.40005 0 270)
			(size 0 0)
			(layers "F.Cu" "F.Mask" "F.Paste")
			(net "GND")
		)
		(pad "2" smd circle
			(at 0.40005 0 270)
			(size 0 0)
			(layers "F.Cu" "F.Mask" "F.Paste")
			(net "PVCCIN_CPU1_VREF")
		)
	)
	(footprint ""
		(layer "F.Cu")
		(at 74.106786 -65.082674 -90)
		(property "Reference" "R3079"
			(at 0 0 270)
			(layer "F.SilkS")
			(hide yes)
			(effects
				(font
					(size 1.27 1.27)
				)
			)
		)
		(property "Value" ""
			(at 0 0 270)
			(layer "F.Fab")
			(effects
				(font
					(size 1.27 1.27)
				)
			)
		)
		(duplicate_pad_numbers_are_jumpers no)
		(fp_line
			(start -0.7874 0.4064)
			(end -0.7874 -0.4064)
			(stroke
				(width 0.1524)
				(type default)
			)
			(layer "F.SilkS")
		)
		(fp_line
			(start 0.7874 0.4064)
			(end -0.7874 0.4064)
			(stroke
				(width 0.1524)
				(type default)
			)
			(layer "F.SilkS")
		)
		(fp_line
			(start -0.7874 -0.4064)
			(end 0.7874 -0.4064)
			(stroke
				(width 0.1524)
				(type default)
			)
			(layer "F.SilkS")
		)
		(fp_line
			(start 0.7874 -0.4064)
			(end 0.7874 0.4064)
			(stroke
				(width 0.1524)
				(type default)
			)
			(layer "F.SilkS")
		)
		(fp_line
			(start -0.67945 0.3048)
			(end -0.67945 -0.305054)
			(stroke
				(width 0.1)
				(type default)
			)
			(layer "F.Fab")
		)
		(fp_line
			(start -0.12065 0.3048)
			(end -0.67945 0.3048)
			(stroke
				(width 0.1)
				(type default)
			)
			(layer "F.Fab")
		)
		(fp_line
			(start 0.120396 0.3048)
			(end 0.120396 0.2794)
			(stroke
				(width 0.1)
				(type default)
			)
			(layer "F.Fab")
		)
		(fp_line
			(start 0.67945 0.3048)
			(end 0.120396 0.3048)
			(stroke
				(width 0.1)
				(type default)
			)
			(layer "F.Fab")
		)
		(fp_line
			(start -0.12065 0.2794)
			(end -0.12065 0.3048)
			(stroke
				(width 0.1)
				(type default)
			)
			(layer "F.Fab")
		)
		(fp_line
			(start 0.120396 0.2794)
			(end -0.12065 0.2794)
			(stroke
				(width 0.1)
				(type default)
			)
			(layer "F.Fab")
		)
		(fp_line
			(start -0.12065 -0.2794)
			(end 0.12065 -0.2794)
			(stroke
				(width 0.1)
				(type default)
			)
			(layer "F.Fab")
		)
		(fp_line
			(start 0.12065 -0.2794)
			(end 0.12065 -0.3048)
			(stroke
				(width 0.1)
				(type default)
			)
			(layer "F.Fab")
		)
		(fp_line
			(start 0.12065 -0.3048)
			(end 0.67945 -0.3048)
			(stroke
				(width 0.1)
				(type default)
			)
			(layer "F.Fab")
		)
		(fp_line
			(start 0.67945 -0.3048)
			(end 0.67945 0.3048)
			(stroke
				(width 0.1)
				(type default)
			)
			(layer "F.Fab")
		)
		(fp_line
			(start -0.67945 -0.305054)
			(end -0.12065 -0.305054)
			(stroke
				(width 0.1)
				(type default)
			)
			(layer "F.Fab")
		)
		(fp_line
			(start -0.12065 -0.305054)
			(end -0.12065 -0.2794)
			(stroke
				(width 0.1)
				(type default)
			)
			(layer "F.Fab")
		)
		(pad "1" smd circle
			(at -0.40005 0 270)
			(size 0 0)
			(layers "F.Cu" "F.Mask" "F.Paste")
			(net "LED_RST_PLD_CPU0_DRAM_EF_N")
		)
		(pad "2" smd circle
			(at 0.40005 0 270)
			(size 0 0)
			(layers "F.Cu" "F.Mask" "F.Paste")
			(net "P3V3_AUX")
		)
	)
	(footprint ""
		(layer "F.Cu")
		(at 79.501238 -402.371052 -90)
		(property "Reference" "C731"
			(at 0 0 270)
			(layer "F.SilkS")
			(hide yes)
			(effects
				(font
					(size 1.27 1.27)
				)
			)
		)
		(property "Value" ""
			(at 0 0 270)
			(layer "F.Fab")
			(effects
				(font
					(size 1.27 1.27)
				)
			)
		)
		(duplicate_pad_numbers_are_jumpers no)
		(fp_line
			(start -0.299974 0.150114)
			(end -0.299974 -0.150114)
			(stroke
				(width 0.1)
				(type default)
			)
			(layer "F.Fab")
		)
		(fp_line
			(start 0.299974 0.150114)
			(end -0.299974 0.150114)
			(stroke
				(width 0.1)
				(type default)
			)
			(layer "F.Fab")
		)
		(fp_line
			(start -0.299974 -0.150114)
			(end 0.299974 -0.150114)
			(stroke
				(width 0.1)
				(type default)
			)
			(layer "F.Fab")
		)
		(fp_line
			(start 0.299974 -0.150114)
			(end 0.299974 0.150114)
			(stroke
				(width 0.1)
				(type default)
			)
			(layer "F.Fab")
		)
		(pad "1" smd rect
			(at -0.2667 0 270)
			(size 0.3048 0.381)
			(layers "F.Cu" "F.Mask" "F.Paste")
			(net "P5E_CPU1_PE0_TX_C_DP<5>")
		)
		(pad "2" smd rect
			(at 0.2667 0 270)
			(size 0.3048 0.381)
			(layers "F.Cu" "F.Mask" "F.Paste")
			(net "P5E_CPU1_PE0_TX_DP<5>")
		)
	)
)
